# TIMECARD (Time Appliance Project (Time Card)) — schematic netlist excerpt (pin names and nets, part order shuffled) for the footprints in the layout excerpt that follows; sources: Cadence DE-HDL packaged netlist, KiCad conversion of R4006-B0001-02_R01.brd

C301  CAPACITOR  10UF 25V 20%  pkg SMC_0805R_H057  page 27 : \1\ = XP12R0V_IN ; \2\ = SG
C131  CAPACITOR  4.7UF 6.3V 20%  pkg SMC_0402R_H026  page 14 : \1\ = XP1R0V_FPGA_MGTAVCC ; \2\ = SG

(kicad_pcb
	(version 20260206)
	(generator "pcbnew")
	(generator_version "10.0")
	(general
		(thickness 1.6)
		(legacy_teardrops no)
	)
	(paper "A4")
	(title_block
		(title "timecard-production-celestica-r4006 — R4006-B0001-02_R01.brd")
		(comment 1 "Time Appliance Project (Time Card) / footprints 1077-1078 of 1113")
	)
	(layers
		(0 "F.Cu" signal "TOP")
		(4 "In1.Cu" signal "L02_GND1")
		(6 "In2.Cu" signal "L03_SIG1")
		(8 "In3.Cu" signal "L04_GND2")
		(10 "In4.Cu" signal "L05_VCC1")
		(12 "In5.Cu" signal "L06_VCC2")
		(14 "In6.Cu" signal "L07_GND3")
		(16 "In7.Cu" signal "L08_SIG2")
		(18 "In8.Cu" signal "L09_GND4")
		(2 "B.Cu" signal "BOTTOM")
		(9 "F.Adhes" user "F.Adhesive")
		(11 "B.Adhes" user "B.Adhesive")
		(13 "F.Paste" user "Package Geometry/Pastemask Top")
		(15 "B.Paste" user "Package Geometry/Pastemask Bottom")
		(5 "F.SilkS" user "Ref Des/Silkscreen Top")
		(7 "B.SilkS" user "Ref Des/Silkscreen Bottom")
		(1 "F.Mask" user "Board Geometry/Soldermask Top")
		(3 "B.Mask" user "Board Geometry/Soldermask Bottom")
		(17 "Dwgs.User" user "User.Drawings")
		(19 "Cmts.User" user "User.Comments")
		(21 "Eco1.User" user "User.Eco1")
		(23 "Eco2.User" user "User.Eco2")
		(25 "Edge.Cuts" user "Board Geometry/Outline")
		(27 "Margin" user)
		(31 "F.CrtYd" user "Package Geometry/Place Bound Top")
		(29 "B.CrtYd" user "Package Geometry/Place Bound Bottom")
		(35 "F.Fab" user "Ref Des/Assembly Top")
		(33 "B.Fab" user "Ref Des/Assembly Bottom")
	)
	(footprint ""
		(layer "B.Cu")
		(at 101.847142 -41.323006 90)
		(property "Reference" "C131"
			(at -0.937006 -42.061892 270)
			(unlocked yes)
			(layer "B.SilkS")
			(effects
				(font
					(size 0.635 0.4064)
					(thickness 0.1524)
				)
				(justify mirror)
			)
		)
		(property "Value" "VAL*"
			(at 0 3.718306 90)
			(unlocked yes)
			(layer "B.Fab")
			(hide yes)
			(effects
				(font
					(size 0.7874 0.5842)
					(thickness 0.127)
				)
				(justify mirror)
			)
		)
		(property "Tolerance" "TOL*"
			(at 0 4.861306 90)
			(unlocked yes)
			(layer "Cmts.User")
			(hide yes)
			(effects
				(font
					(size 0.7874 0.5842)
					(thickness 0.127)
				)
				(justify mirror)
			)
		)
		(property "User Part Number" "PARTNUM*"
			(at 0 2.575306 90)
			(unlocked yes)
			(layer "Cmts.User")
			(hide yes)
			(effects
				(font
					(size 0.7874 0.5842)
					(thickness 0.127)
				)
				(justify mirror)
			)
		)
		(property "Device Type" "CAPACITOR-G105-0F475-BM,4.7UF,A"
			(at 0 1.432306 90)
			(unlocked yes)
			(layer "B.Fab")
			(hide yes)
			(effects
				(font
					(size 0.7874 0.5842)
					(thickness 0.127)
				)
				(justify mirror)
			)
		)
		(duplicate_pad_numbers_are_jumpers no)
		(fp_line
			(start 0.970026 -0.4699)
			(end -0.970026 -0.4699)
			(stroke
				(width 0.1)
				(type default)
			)
			(layer "B.SilkS")
		)
		(fp_line
			(start -0.970026 -0.4699)
			(end -0.970026 0.4699)
			(stroke
				(width 0.1)
				(type default)
			)
			(layer "B.SilkS")
		)
		(fp_line
			(start 0.970026 0.4699)
			(end 0.970026 -0.4699)
			(stroke
				(width 0.1)
				(type default)
			)
			(layer "B.SilkS")
		)
		(fp_line
			(start -0.970026 0.4699)
			(end 0.970026 0.4699)
			(stroke
				(width 0.1)
				(type default)
			)
			(layer "B.SilkS")
		)
		(fp_poly
			(pts
				(xy 0.970026 0.4699) (xy -0.970026 0.4699) (xy -0.970026 -0.4699) (xy 0.970026 -0.4699)
			)
			(stroke
				(width 0)
				(type default)
			)
			(fill no)
			(layer "B.CrtYd")
		)
		(fp_line
			(start 0.508 -0.3048)
			(end -0.508 -0.3048)
			(stroke
				(width 0.1)
				(type default)
			)
			(layer "B.Fab")
		)
		(fp_line
			(start -0.508 -0.3048)
			(end -0.508 0.3048)
			(stroke
				(width 0.1)
				(type default)
			)
			(layer "B.Fab")
		)
		(fp_line
			(start 0.508 0.3048)
			(end 0.508 -0.3048)
			(stroke
				(width 0.1)
				(type default)
			)
			(layer "B.Fab")
		)
		(fp_line
			(start -0.508 0.3048)
			(end 0.508 0.3048)
			(stroke
				(width 0.1)
				(type default)
			)
			(layer "B.Fab")
		)
		(pad "1" smd circle
			(at 0.500126 0 270)
			(size 0.635 0.635)
			(layers "B.Cu" "B.Mask" "B.Paste")
			(net "XP1R0V_FPGA_MGTAVCC")
		)
		(pad "2" smd circle
			(at -0.500126 0 270)
			(size 0.635 0.635)
			(layers "B.Cu" "B.Mask" "B.Paste")
			(net "SG")
		)
	)
	(footprint ""
		(layer "B.Cu")
		(at 139.6492 -87.4014)
		(property "Reference" "C301"
			(at 0.3048 -5.01523 0)
			(unlocked yes)
			(layer "B.SilkS")
			(effects
				(font
					(size 0.7874 0.5842)
					(thickness 0.1524)
				)
				(justify mirror)
			)
		)
		(property "Value" "VAL*"
			(at -0.0762 3.134106 0)
			(unlocked yes)
			(layer "B.Fab")
			(hide yes)
			(effects
				(font
					(size 0.7874 0.5842)
					(thickness 0.1524)
				)
				(justify mirror)
			)
		)
		(property "Tolerance" "TOL*"
			(at -0.0762 4.048506 0)
			(unlocked yes)
			(layer "Cmts.User")
			(hide yes)
			(effects
				(font
					(size 0.7874 0.5842)
					(thickness 0.1524)
				)
				(justify mirror)
			)
		)
		(property "User Part Number" "PARTNUM*"
			(at -0.1016 5.013706 0)
			(unlocked yes)
			(layer "Cmts.User")
			(hide yes)
			(effects
				(font
					(size 0.7874 0.5842)
					(thickness 0.1524)
				)
				(justify mirror)
			)
		)
		(property "Device Type" "CAPACITOR-G107-0F106-EM,10UF,2A"
			(at -0.0508 2.194306 0)
			(unlocked yes)
			(layer "B.Fab")
			(hide yes)
			(effects
				(font
					(size 0.7874 0.5842)
					(thickness 0.1524)
				)
				(justify mirror)
			)
		)
		(duplicate_pad_numbers_are_jumpers no)
		(fp_line
			(start -1.5748 -0.9398)
			(end 1.5748 -0.9398)
			(stroke
				(width 0.1)
				(type default)
			)
			(layer "B.SilkS")
		)
		(fp_line
			(start -1.5748 0.9398)
			(end -1.5748 -0.9398)
			(stroke
				(width 0.1)
				(type default)
			)
			(layer "B.SilkS")
		)
		(fp_line
			(start 1.5748 -0.9398)
			(end 1.5748 0.9398)
			(stroke
				(width 0.1)
				(type default)
			)
			(layer "B.SilkS")
		)
		(fp_line
			(start 1.5748 0.9398)
			(end -1.5748 0.9398)
			(stroke
				(width 0.1)
				(type default)
			)
			(layer "B.SilkS")
		)
		(fp_rect
			(start 1.5748 0.9398)
			(end -1.5748 -0.9398)
			(stroke
				(width 0)
				(type default)
			)
			(fill no)
			(layer "B.CrtYd")
		)
		(fp_line
			(start -1.016 -0.635)
			(end 1.016 -0.635)
			(stroke
				(width 0.1)
				(type default)
			)
			(layer "B.Fab")
		)
		(fp_line
			(start -1.016 0.635)
			(end -1.016 -0.635)
			(stroke
				(width 0.1)
				(type default)
			)
			(layer "B.Fab")
		)
		(fp_line
			(start 1.016 -0.635)
			(end 1.016 0.635)
			(stroke
				(width 0.1)
				(type default)
			)
			(layer "B.Fab")
		)
		(fp_line
			(start 1.016 0.635)
			(end -1.016 0.635)
			(stroke
				(width 0.1)
				(type default)
			)
			(layer "B.Fab")
		)
		(pad "1" smd rect
			(at 0.8382 0 180)
			(size 0.9652 1.3716)
			(layers "B.Cu" "B.Mask" "B.Paste")
			(net "XP12R0V_IN")
		)
		(pad "2" smd rect
			(at -0.8382 0 180)
			(size 0.9652 1.3716)
			(layers "B.Cu" "B.Mask" "B.Paste")
			(net "SG")
		)
		(zone
			(layer "B.Cu")
			(hatch none 0.5)
			(connect_pads
				(clearance 0)
			)
			(min_thickness 0.25)
			(keepout
				(tracks not_allowed)
				(vias allowed)
				(pads allowed)
				(copperpour not_allowed)
				(footprints allowed)
			)
			(placement
				(enabled no)
				(sheetname "")
			)
			(fill
				(thermal_gap 0.5)
				(thermal_bridge_width 0.5)
				(island_removal_mode 0)
			)
			(polygon
				(pts
					(xy 139.8778 -86.7664) (xy 139.8778 -88.0364) (xy 139.4206 -88.0364) (xy 139.4206 -86.7664)
				)
			)
		)
		(zone
			(layer "B.Cu")
			(hatch none 0.5)
			(connect_pads
				(clearance 0)
			)
			(min_thickness 0.25)
			(keepout
				(tracks allowed)
				(vias not_allowed)
				(pads allowed)
				(copperpour not_allowed)
				(footprints allowed)
			)
			(placement
				(enabled no)
				(sheetname "")
			)
			(fill
				(thermal_gap 0.5)
				(thermal_bridge_width 0.5)
				(island_removal_mode 0)
			)
			(polygon
				(pts
					(xy 139.8778 -86.7664) (xy 139.8778 -88.0364) (xy 139.4206 -88.0364) (xy 139.4206 -86.7664)
				)
			)
		)
	)
)
